# S9S_MB_2U (Grand Teton) — schematic netlist excerpt (pin names and nets, part order shuffled) for the footprints in the layout excerpt that follows; sources: Cadence DE-HDL packaged netlist, KiCad conversion of 03242023_DA0F0TMBIJ0_F0T_Motherboard_J_brd_V01_OCP.brd

R3123  Q_RES  0 5% CHIP  pkg 0402LF  page 236 : A = SMB_S3M_CPU0_PIROM_3V3AUX_SCL_R ; B = SMB_S3M_CPU0_PIROM_3V3AUX_SCL
R3518  Q_RES  0 5% CHIP  pkg 0402LF  page 227 : A = GPU_PEX_STRAP0 ; B = GPU_PEX_STRAP0_R

(kicad_pcb
	(version 20260206)
	(generator "pcbnew")
	(generator_version "10.0")
	(general
		(thickness 1.6)
		(legacy_teardrops no)
	)
	(paper "A4")
	(title_block
		(title "03242023_DA0F0TMBIJ0_F0T_Motherboard_J_brd_V01_OCP.brd")
		(comment 1 "Grand Teton / footprints 1670-1671 of 6105")
	)
	(layers
		(0 "F.Cu" signal "TOP")
		(4 "In1.Cu" signal "GND")
		(6 "In2.Cu" signal "IN1")
		(8 "In3.Cu" signal "GND1")
		(10 "In4.Cu" signal "IN2")
		(12 "In5.Cu" signal "GND2")
		(14 "In6.Cu" signal "IN3")
		(16 "In7.Cu" signal "GND3")
		(18 "In8.Cu" signal "VCC")
		(20 "In9.Cu" signal "VCC1")
		(22 "In10.Cu" signal "GND4")
		(24 "In11.Cu" signal "IN4")
		(26 "In12.Cu" signal "GND5")
		(28 "In13.Cu" signal "IN5")
		(30 "In14.Cu" signal "GND6")
		(32 "In15.Cu" signal "IN6")
		(34 "In16.Cu" signal "GND7")
		(2 "B.Cu" signal "BOTTOM")
		(9 "F.Adhes" user "F.Adhesive")
		(11 "B.Adhes" user "B.Adhesive")
		(13 "F.Paste" user "Package Geometry/Pastemask Top")
		(15 "B.Paste" user "Package Geometry/Pastemask Bottom")
		(5 "F.SilkS" user "Ref Des/Silkscreen Top")
		(7 "B.SilkS" user "Ref Des/Silkscreen Bottom")
		(1 "F.Mask" user "Board Geometry/Soldermask Top")
		(3 "B.Mask" user "Board Geometry/Soldermask Bottom")
		(17 "Dwgs.User" user "User.Drawings")
		(19 "Cmts.User" user "User.Comments")
		(21 "Eco1.User" user "User.Eco1")
		(23 "Eco2.User" user "User.Eco2")
		(25 "Edge.Cuts" user "Board Geometry/Outline")
		(27 "Margin" user)
		(31 "F.CrtYd" user "Package Geometry/Place Bound Top")
		(29 "B.CrtYd" user "Package Geometry/Place Bound Bottom")
		(35 "F.Fab" user "Ref Des/Assembly Top")
		(33 "B.Fab" user "Ref Des/Assembly Bottom")
	)
	(footprint ""
		(layer "F.Cu")
		(at 155.348686 -81.89468 90)
		(property "Reference" "R3123"
			(at 0 0 90)
			(layer "F.SilkS")
			(hide yes)
			(effects
				(font
					(size 1.27 1.27)
				)
			)
		)
		(property "Value" ""
			(at 0 0 90)
			(layer "F.Fab")
			(effects
				(font
					(size 1.27 1.27)
				)
			)
		)
		(duplicate_pad_numbers_are_jumpers no)
		(fp_line
			(start 0.7874 -0.4064)
			(end 0.7874 0.4064)
			(stroke
				(width 0.1524)
				(type default)
			)
			(layer "F.SilkS")
		)
		(fp_line
			(start -0.7874 -0.4064)
			(end 0.7874 -0.4064)
			(stroke
				(width 0.1524)
				(type default)
			)
			(layer "F.SilkS")
		)
		(fp_line
			(start 0.7874 0.4064)
			(end -0.7874 0.4064)
			(stroke
				(width 0.1524)
				(type default)
			)
			(layer "F.SilkS")
		)
		(fp_line
			(start -0.7874 0.4064)
			(end -0.7874 -0.4064)
			(stroke
				(width 0.1524)
				(type default)
			)
			(layer "F.SilkS")
		)
		(fp_line
			(start -0.12065 -0.305054)
			(end -0.12065 -0.2794)
			(stroke
				(width 0.1)
				(type default)
			)
			(layer "F.Fab")
		)
		(fp_line
			(start -0.67945 -0.305054)
			(end -0.12065 -0.305054)
			(stroke
				(width 0.1)
				(type default)
			)
			(layer "F.Fab")
		)
		(fp_line
			(start 0.67945 -0.3048)
			(end 0.67945 0.3048)
			(stroke
				(width 0.1)
				(type default)
			)
			(layer "F.Fab")
		)
		(fp_line
			(start 0.12065 -0.3048)
			(end 0.67945 -0.3048)
			(stroke
				(width 0.1)
				(type default)
			)
			(layer "F.Fab")
		)
		(fp_line
			(start 0.12065 -0.2794)
			(end 0.12065 -0.3048)
			(stroke
				(width 0.1)
				(type default)
			)
			(layer "F.Fab")
		)
		(fp_line
			(start -0.12065 -0.2794)
			(end 0.12065 -0.2794)
			(stroke
				(width 0.1)
				(type default)
			)
			(layer "F.Fab")
		)
		(fp_line
			(start 0.120396 0.2794)
			(end -0.12065 0.2794)
			(stroke
				(width 0.1)
				(type default)
			)
			(layer "F.Fab")
		)
		(fp_line
			(start -0.12065 0.2794)
			(end -0.12065 0.3048)
			(stroke
				(width 0.1)
				(type default)
			)
			(layer "F.Fab")
		)
		(fp_line
			(start 0.67945 0.3048)
			(end 0.120396 0.3048)
			(stroke
				(width 0.1)
				(type default)
			)
			(layer "F.Fab")
		)
		(fp_line
			(start 0.120396 0.3048)
			(end 0.120396 0.2794)
			(stroke
				(width 0.1)
				(type default)
			)
			(layer "F.Fab")
		)
		(fp_line
			(start -0.12065 0.3048)
			(end -0.67945 0.3048)
			(stroke
				(width 0.1)
				(type default)
			)
			(layer "F.Fab")
		)
		(fp_line
			(start -0.67945 0.3048)
			(end -0.67945 -0.305054)
			(stroke
				(width 0.1)
				(type default)
			)
			(layer "F.Fab")
		)
		(pad "1" smd circle
			(at -0.40005 0 90)
			(size 0 0)
			(layers "F.Cu" "F.Mask" "F.Paste")
			(net "SMB_S3M_CPU0_PIROM_3V3AUX_SCL_R")
		)
		(pad "2" smd circle
			(at 0.40005 0 90)
			(size 0 0)
			(layers "F.Cu" "F.Mask" "F.Paste")
			(net "SMB_S3M_CPU0_PIROM_3V3AUX_SCL")
		)
	)
	(footprint ""
		(layer "F.Cu")
		(at 18.753582 -423.629836 -90)
		(property "Reference" "R3518"
			(at 0 0 270)
			(layer "F.SilkS")
			(hide yes)
			(effects
				(font
					(size 1.27 1.27)
				)
			)
		)
		(property "Value" ""
			(at 0 0 270)
			(layer "F.Fab")
			(effects
				(font
					(size 1.27 1.27)
				)
			)
		)
		(duplicate_pad_numbers_are_jumpers no)
		(fp_line
			(start -0.7874 0.4064)
			(end -0.7874 -0.4064)
			(stroke
				(width 0.1524)
				(type default)
			)
			(layer "F.SilkS")
		)
		(fp_line
			(start 0.7874 0.4064)
			(end -0.7874 0.4064)
			(stroke
				(width 0.1524)
				(type default)
			)
			(layer "F.SilkS")
		)
		(fp_line
			(start -0.7874 -0.4064)
			(end 0.7874 -0.4064)
			(stroke
				(width 0.1524)
				(type default)
			)
			(layer "F.SilkS")
		)
		(fp_line
			(start 0.7874 -0.4064)
			(end 0.7874 0.4064)
			(stroke
				(width 0.1524)
				(type default)
			)
			(layer "F.SilkS")
		)
		(fp_line
			(start -0.67945 0.3048)
			(end -0.67945 -0.305054)
			(stroke
				(width 0.1)
				(type default)
			)
			(layer "F.Fab")
		)
		(fp_line
			(start -0.12065 0.3048)
			(end -0.67945 0.3048)
			(stroke
				(width 0.1)
				(type default)
			)
			(layer "F.Fab")
		)
		(fp_line
			(start 0.120396 0.3048)
			(end 0.120396 0.2794)
			(stroke
				(width 0.1)
				(type default)
			)
			(layer "F.Fab")
		)
		(fp_line
			(start 0.67945 0.3048)
			(end 0.120396 0.3048)
			(stroke
				(width 0.1)
				(type default)
			)
			(layer "F.Fab")
		)
		(fp_line
			(start -0.12065 0.2794)
			(end -0.12065 0.3048)
			(stroke
				(width 0.1)
				(type default)
			)
			(layer "F.Fab")
		)
		(fp_line
			(start 0.120396 0.2794)
			(end -0.12065 0.2794)
			(stroke
				(width 0.1)
				(type default)
			)
			(layer "F.Fab")
		)
		(fp_line
			(start -0.12065 -0.2794)
			(end 0.12065 -0.2794)
			(stroke
				(width 0.1)
				(type default)
			)
			(layer "F.Fab")
		)
		(fp_line
			(start 0.12065 -0.2794)
			(end 0.12065 -0.3048)
			(stroke
				(width 0.1)
				(type default)
			)
			(layer "F.Fab")
		)
		(fp_line
			(start 0.12065 -0.3048)
			(end 0.67945 -0.3048)
			(stroke
				(width 0.1)
				(type default)
			)
			(layer "F.Fab")
		)
		(fp_line
			(start 0.67945 -0.3048)
			(end 0.67945 0.3048)
			(stroke
				(width 0.1)
				(type default)
			)
			(layer "F.Fab")
		)
		(fp_line
			(start -0.67945 -0.305054)
			(end -0.12065 -0.305054)
			(stroke
				(width 0.1)
				(type default)
			)
			(layer "F.Fab")
		)
		(fp_line
			(start -0.12065 -0.305054)
			(end -0.12065 -0.2794)
			(stroke
				(width 0.1)
				(type default)
			)
			(layer "F.Fab")
		)
		(pad "1" smd circle
			(at -0.40005 0 270)
			(size 0 0)
			(layers "F.Cu" "F.Mask" "F.Paste")
			(net "GPU_PEX_STRAP0")
		)
		(pad "2" smd circle
			(at 0.40005 0 270)
			(size 0 0)
			(layers "F.Cu" "F.Mask" "F.Paste")
			(net "GPU_PEX_STRAP0_R")
		)
	)
)
